# TIMECARD (Time Appliance Project (Time Card)) — schematic netlist excerpt (pin names and nets, part order shuffled) for the footprints in the layout excerpt that follows; sources: Cadence DE-HDL packaged netlist, KiCad conversion of R4006-B0001-02_R01.brd

R62  RESISTOR  0OHM -  pkg SMC_0402R_H016  page 16 : \1\ = VDD_PCA9546A ; \2\ = XP3R3V_FPGA
C123  CAPACITOR  0.1UF 25V 10%  pkg SMC_0402R_H022  page 24 : \1\ = XP3R3V_FPGA ; \2\ = SG

(kicad_pcb
	(version 20260206)
	(generator "pcbnew")
	(generator_version "10.0")
	(general
		(thickness 1.6)
		(legacy_teardrops no)
	)
	(paper "A4")
	(title_block
		(title "timecard-production-celestica-r4006 — R4006-B0001-02_R01.brd")
		(comment 1 "Time Appliance Project (Time Card) / footprints 1085-1086 of 1113")
	)
	(layers
		(0 "F.Cu" signal "TOP")
		(4 "In1.Cu" signal "L02_GND1")
		(6 "In2.Cu" signal "L03_SIG1")
		(8 "In3.Cu" signal "L04_GND2")
		(10 "In4.Cu" signal "L05_VCC1")
		(12 "In5.Cu" signal "L06_VCC2")
		(14 "In6.Cu" signal "L07_GND3")
		(16 "In7.Cu" signal "L08_SIG2")
		(18 "In8.Cu" signal "L09_GND4")
		(2 "B.Cu" signal "BOTTOM")
		(9 "F.Adhes" user "F.Adhesive")
		(11 "B.Adhes" user "B.Adhesive")
		(13 "F.Paste" user "Package Geometry/Pastemask Top")
		(15 "B.Paste" user "Package Geometry/Pastemask Bottom")
		(5 "F.SilkS" user "Ref Des/Silkscreen Top")
		(7 "B.SilkS" user "Ref Des/Silkscreen Bottom")
		(1 "F.Mask" user "Board Geometry/Soldermask Top")
		(3 "B.Mask" user "Board Geometry/Soldermask Bottom")
		(17 "Dwgs.User" user "User.Drawings")
		(19 "Cmts.User" user "User.Comments")
		(21 "Eco1.User" user "User.Eco1")
		(23 "Eco2.User" user "User.Eco2")
		(25 "Edge.Cuts" user "Board Geometry/Outline")
		(27 "Margin" user)
		(31 "F.CrtYd" user "Package Geometry/Place Bound Top")
		(29 "B.CrtYd" user "Package Geometry/Place Bound Bottom")
		(35 "F.Fab" user "Ref Des/Assembly Top")
		(33 "B.Fab" user "Ref Des/Assembly Bottom")
	)
	(footprint ""
		(layer "B.Cu")
		(at 101.092 -87.63 -90)
		(property "Reference" "C123"
			(at 0.127 -1.23063 270)
			(unlocked yes)
			(layer "B.SilkS")
			(effects
				(font
					(size 0.7874 0.5842)
					(thickness 0.1524)
				)
				(justify mirror)
			)
		)
		(property "Value" "VAL*"
			(at -0.0762 2.067306 270)
			(unlocked yes)
			(layer "B.Fab")
			(hide yes)
			(effects
				(font
					(size 0.7874 0.5842)
					(thickness 0.1524)
				)
				(justify mirror)
			)
		)
		(property "Tolerance" "TOL*"
			(at -0.0762 3.032506 270)
			(unlocked yes)
			(layer "Cmts.User")
			(hide yes)
			(effects
				(font
					(size 0.7874 0.5842)
					(thickness 0.1524)
				)
				(justify mirror)
			)
		)
		(property "User Part Number" "PARTNUM*"
			(at -0.1016 4.023106 270)
			(unlocked yes)
			(layer "Cmts.User")
			(hide yes)
			(effects
				(font
					(size 0.7874 0.5842)
					(thickness 0.1524)
				)
				(justify mirror)
			)
		)
		(property "Device Type" "CAPACITOR-G105-0B104-EK,0.1UF,A"
			(at -0.0508 1.127506 270)
			(unlocked yes)
			(layer "B.Fab")
			(hide yes)
			(effects
				(font
					(size 0.7874 0.5842)
					(thickness 0.1524)
				)
				(justify mirror)
			)
		)
		(duplicate_pad_numbers_are_jumpers no)
		(fp_line
			(start -1.143 0.5588)
			(end -1.143 -0.5588)
			(stroke
				(width 0.1)
				(type default)
			)
			(layer "B.SilkS")
		)
		(fp_line
			(start 1.143 0.5588)
			(end -1.143 0.5588)
			(stroke
				(width 0.1)
				(type default)
			)
			(layer "B.SilkS")
		)
		(fp_line
			(start -1.143 -0.5588)
			(end 1.143 -0.5588)
			(stroke
				(width 0.1)
				(type default)
			)
			(layer "B.SilkS")
		)
		(fp_line
			(start 1.143 -0.5588)
			(end 1.143 0.5588)
			(stroke
				(width 0.1)
				(type default)
			)
			(layer "B.SilkS")
		)
		(fp_poly
			(pts
				(xy 1.143 0.5588) (xy -1.143 0.5588) (xy -1.143 -0.5588) (xy 1.143 -0.5588)
			)
			(stroke
				(width 0)
				(type default)
			)
			(fill no)
			(layer "B.CrtYd")
		)
		(fp_line
			(start -0.508 0.3048)
			(end -0.508 -0.3048)
			(stroke
				(width 0.1)
				(type default)
			)
			(layer "B.Fab")
		)
		(fp_line
			(start 0.508 0.3048)
			(end -0.508 0.3048)
			(stroke
				(width 0.1)
				(type default)
			)
			(layer "B.Fab")
		)
		(fp_line
			(start -0.508 -0.3048)
			(end 0.508 -0.3048)
			(stroke
				(width 0.1)
				(type default)
			)
			(layer "B.Fab")
		)
		(fp_line
			(start 0.508 -0.3048)
			(end 0.508 0.3048)
			(stroke
				(width 0.1)
				(type default)
			)
			(layer "B.Fab")
		)
		(pad "1" smd rect
			(at 0.5334 0 90)
			(size 0.7112 0.6096)
			(layers "B.Cu" "B.Mask" "B.Paste")
			(net "XP3R3V_FPGA")
		)
		(pad "2" smd rect
			(at -0.5334 0 90)
			(size 0.7112 0.6096)
			(layers "B.Cu" "B.Mask" "B.Paste")
			(net "SG")
		)
		(zone
			(layer "B.Cu")
			(hatch none 0.5)
			(connect_pads
				(clearance 0)
			)
			(min_thickness 0.25)
			(keepout
				(tracks not_allowed)
				(vias allowed)
				(pads allowed)
				(copperpour not_allowed)
				(footprints allowed)
			)
			(placement
				(enabled no)
				(sheetname "")
			)
			(fill
				(thermal_gap 0.5)
				(thermal_bridge_width 0.5)
				(island_removal_mode 0)
			)
			(polygon
				(pts
					(xy 100.7872 -87.5538) (xy 101.3968 -87.5538) (xy 101.3968 -87.7062) (xy 100.7872 -87.7062)
				)
			)
		)
		(zone
			(layer "B.Cu")
			(hatch none 0.5)
			(connect_pads
				(clearance 0)
			)
			(min_thickness 0.25)
			(keepout
				(tracks allowed)
				(vias not_allowed)
				(pads allowed)
				(copperpour not_allowed)
				(footprints allowed)
			)
			(placement
				(enabled no)
				(sheetname "")
			)
			(fill
				(thermal_gap 0.5)
				(thermal_bridge_width 0.5)
				(island_removal_mode 0)
			)
			(polygon
				(pts
					(xy 100.7872 -87.5538) (xy 101.3968 -87.5538) (xy 101.3968 -87.7062) (xy 100.7872 -87.7062)
				)
			)
		)
	)
	(footprint ""
		(layer "B.Cu")
		(at 77.3938 -82.804 180)
		(property "Reference" "R62"
			(at 2.9718 -0.29337 0)
			(unlocked yes)
			(layer "B.SilkS")
			(effects
				(font
					(size 0.7874 0.5842)
					(thickness 0.1524)
				)
				(justify mirror)
			)
		)
		(property "Value" "VAL*"
			(at -0.02032 2.13233 180)
			(unlocked yes)
			(layer "B.Fab")
			(hide yes)
			(effects
				(font
					(size 0.7874 0.5842)
					(thickness 0.1524)
				)
				(justify mirror)
			)
		)
		(property "Tolerance" "TOL*"
			(at -0.044704 3.05435 180)
			(unlocked yes)
			(layer "Cmts.User")
			(hide yes)
			(effects
				(font
					(size 0.7874 0.5842)
					(thickness 0.1524)
				)
				(justify mirror)
			)
		)
		(property "User Part Number" "PARTNUM*"
			(at -0.02032 4.024884 180)
			(unlocked yes)
			(layer "Cmts.User")
			(hide yes)
			(effects
				(font
					(size 0.7874 0.5842)
					(thickness 0.1524)
				)
				(justify mirror)
			)
		)
		(property "Device Type" "RESISTOR-G155-100R0-J0,0OHM,-"
			(at -0.008382 1.210564 180)
			(unlocked yes)
			(layer "B.Fab")
			(hide yes)
			(effects
				(font
					(size 0.7874 0.5842)
					(thickness 0.1524)
				)
				(justify mirror)
			)
		)
		(duplicate_pad_numbers_are_jumpers no)
		(fp_line
			(start 1.143 0.5588)
			(end -1.143 0.5588)
			(stroke
				(width 0.1)
				(type default)
			)
			(layer "B.SilkS")
		)
		(fp_line
			(start 1.143 -0.5588)
			(end 1.143 0.5588)
			(stroke
				(width 0.1)
				(type default)
			)
			(layer "B.SilkS")
		)
		(fp_line
			(start -1.143 0.5588)
			(end -1.143 -0.5588)
			(stroke
				(width 0.1)
				(type default)
			)
			(layer "B.SilkS")
		)
		(fp_line
			(start -1.143 -0.5588)
			(end 1.143 -0.5588)
			(stroke
				(width 0.1)
				(type default)
			)
			(layer "B.SilkS")
		)
		(fp_poly
			(pts
				(xy 1.143 0.5588) (xy -1.143 0.5588) (xy -1.143 -0.5588) (xy 1.143 -0.5588)
			)
			(stroke
				(width 0)
				(type default)
			)
			(fill no)
			(layer "B.CrtYd")
		)
		(fp_line
			(start 0.508 0.3048)
			(end -0.508 0.3048)
			(stroke
				(width 0.1)
				(type default)
			)
			(layer "B.Fab")
		)
		(fp_line
			(start 0.508 -0.3048)
			(end 0.508 0.3048)
			(stroke
				(width 0.1)
				(type default)
			)
			(layer "B.Fab")
		)
		(fp_line
			(start -0.508 0.3048)
			(end -0.508 -0.3048)
			(stroke
				(width 0.1)
				(type default)
			)
			(layer "B.Fab")
		)
		(fp_line
			(start -0.508 -0.3048)
			(end 0.508 -0.3048)
			(stroke
				(width 0.1)
				(type default)
			)
			(layer "B.Fab")
		)
		(pad "1" smd rect
			(at 0.5334 0)
			(size 0.7112 0.6096)
			(layers "B.Cu" "B.Mask" "B.Paste")
			(net "VDD_PCA9546A")
		)
		(pad "2" smd rect
			(at -0.5334 0)
			(size 0.7112 0.6096)
			(layers "B.Cu" "B.Mask" "B.Paste")
			(net "XP3R3V_FPGA")
		)
		(zone
			(layer "B.Cu")
			(hatch none 0.5)
			(connect_pads
				(clearance 0)
			)
			(min_thickness 0.25)
			(keepout
				(tracks allowed)
				(vias not_allowed)
				(pads allowed)
				(copperpour not_allowed)
				(footprints allowed)
			)
			(placement
				(enabled no)
				(sheetname "")
			)
			(fill
				(thermal_gap 0.5)
				(thermal_bridge_width 0.5)
				(island_removal_mode 0)
			)
			(polygon
				(pts
					(xy 77.3176 -83.1088) (xy 77.3176 -82.4992) (xy 77.47 -82.4992) (xy 77.47 -83.1088)
				)
			)
		)
		(zone
			(layer "B.Cu")
			(hatch none 0.5)
			(connect_pads
				(clearance 0)
			)
			(min_thickness 0.25)
			(keepout
				(tracks not_allowed)
				(vias allowed)
				(pads allowed)
				(copperpour not_allowed)
				(footprints allowed)
			)
			(placement
				(enabled no)
				(sheetname "")
			)
			(fill
				(thermal_gap 0.5)
				(thermal_bridge_width 0.5)
				(island_removal_mode 0)
			)
			(polygon
				(pts
					(xy 77.3176 -83.1088) (xy 77.3176 -82.4992) (xy 77.47 -82.4992) (xy 77.47 -83.1088)
				)
			)
		)
	)
)
